# BASEBOARD_FAB2 (Tioga Pass) — schematic netlist excerpt (pin names and nets, part order shuffled) for the footprints in the layout excerpt that follows; sources: Cadence DE-HDL packaged netlist, KiCad conversion of Wiwynn_Tioga_Pass_MB.brd

C1F18  CAP  0.22UF 16V 10% X7R  pkg 0402  page 181 : A = P3E_CPU1_PE3_MP_C_TXP<0> ; B = P3E_CPU1_PE3_MP_TXP<0>
C1C2  CAPP  270UF 16V 20% OSCON  pkg 2626  page 209 : A = VR_FET_SW_P12V_STBY_PVCCIN_CPU1 ; B = GND

(kicad_pcb
	(version 20260206)
	(generator "pcbnew")
	(generator_version "10.0")
	(general
		(thickness 1.6)
		(legacy_teardrops no)
	)
	(paper "A4")
	(title_block
		(title "Wiwynn_Tioga_Pass_MB.brd")
		(comment 1 "Tioga Pass / footprints 2174-2175 of 4770")
	)
	(layers
		(0 "F.Cu" signal "TOP")
		(4 "In1.Cu" signal "L2GND")
		(6 "In2.Cu" signal "L3")
		(8 "In3.Cu" signal "L4GND")
		(10 "In4.Cu" signal "L5")
		(12 "In5.Cu" signal "L6GND")
		(14 "In6.Cu" signal "L7VCC")
		(16 "In7.Cu" signal "L8VCC")
		(18 "In8.Cu" signal "L9GND")
		(20 "In9.Cu" signal "L10")
		(22 "In10.Cu" signal "L11GND")
		(24 "In11.Cu" signal "L12")
		(26 "In12.Cu" signal "L13GND")
		(2 "B.Cu" signal "BOTTOM")
		(9 "F.Adhes" user "F.Adhesive")
		(11 "B.Adhes" user "B.Adhesive")
		(13 "F.Paste" user "Package Geometry/Pastemask Top")
		(15 "B.Paste" user "Package Geometry/Pastemask Bottom")
		(5 "F.SilkS" user "Ref Des/Silkscreen Top")
		(7 "B.SilkS" user "Ref Des/Silkscreen Bottom")
		(1 "F.Mask" user "Board Geometry/Soldermask Top")
		(3 "B.Mask" user "Board Geometry/Soldermask Bottom")
		(17 "Dwgs.User" user "User.Drawings")
		(19 "Cmts.User" user "User.Comments")
		(21 "Eco1.User" user "User.Eco1")
		(23 "Eco2.User" user "User.Eco2")
		(25 "Edge.Cuts" user "Board Geometry/Outline")
		(27 "Margin" user)
		(31 "F.CrtYd" user "Package Geometry/Place Bound Top")
		(29 "B.CrtYd" user "Package Geometry/Place Bound Bottom")
		(35 "F.Fab" user "Ref Des/Assembly Top")
		(33 "B.Fab" user "Ref Des/Assembly Bottom")
	)
	(footprint ""
		(layer "F.Cu")
		(at 25.521158 -102.40772 -90)
		(property "Reference" "C1C2"
			(at 4.445 -1.55067 90)
			(unlocked yes)
			(layer "F.SilkS")
			(effects
				(font
					(size 0.7874 0.5842)
					(thickness 0.1524)
				)
				(justify left)
			)
		)
		(property "Value" ""
			(at 0 0 270)
			(layer "F.Fab")
			(effects
				(font
					(size 1.27 1.27)
				)
			)
		)
		(duplicate_pad_numbers_are_jumpers no)
		(fp_line
			(start -3.400044 6.067044)
			(end -0.9017 6.067044)
			(stroke
				(width 0.1524)
				(type default)
			)
			(layer "F.SilkS")
		)
		(fp_line
			(start 0.9017 6.067044)
			(end 3.400044 6.067044)
			(stroke
				(width 0.1524)
				(type default)
			)
			(layer "F.SilkS")
		)
		(fp_line
			(start 3.400044 6.067044)
			(end 3.400044 0.028956)
			(stroke
				(width 0.1524)
				(type default)
			)
			(layer "F.SilkS")
		)
		(fp_line
			(start -0.9017 1.587754)
			(end -0.7239 1.587754)
			(stroke
				(width 0.1524)
				(type default)
			)
			(layer "F.SilkS")
		)
		(fp_line
			(start 0.7239 1.587754)
			(end 0.9017 1.587754)
			(stroke
				(width 0.1524)
				(type default)
			)
			(layer "F.SilkS")
		)
		(fp_line
			(start 0.9017 1.587754)
			(end 0.9017 -1.714246)
			(stroke
				(width 0.1524)
				(type default)
			)
			(layer "F.SilkS")
		)
		(fp_line
			(start -3.400044 0.028956)
			(end -3.400044 6.067044)
			(stroke
				(width 0.1524)
				(type default)
			)
			(layer "F.SilkS")
		)
		(fp_line
			(start 3.400044 0.028956)
			(end 2.638044 -0.733044)
			(stroke
				(width 0.1524)
				(type default)
			)
			(layer "F.SilkS")
		)
		(fp_line
			(start -2.638044 -0.733044)
			(end -3.400044 0.028956)
			(stroke
				(width 0.1524)
				(type default)
			)
			(layer "F.SilkS")
		)
		(fp_line
			(start -0.9017 -0.733044)
			(end -2.638044 -0.733044)
			(stroke
				(width 0.1524)
				(type default)
			)
			(layer "F.SilkS")
		)
		(fp_line
			(start 2.638044 -0.733044)
			(end 0.9017 -0.733044)
			(stroke
				(width 0.1524)
				(type default)
			)
			(layer "F.SilkS")
		)
		(fp_line
			(start -0.9017 -1.714246)
			(end -0.9017 1.587754)
			(stroke
				(width 0.1524)
				(type default)
			)
			(layer "F.SilkS")
		)
		(fp_line
			(start -0.7239 -1.714246)
			(end -0.9017 -1.714246)
			(stroke
				(width 0.1524)
				(type default)
			)
			(layer "F.SilkS")
		)
		(fp_line
			(start 0.9017 -1.714246)
			(end 0.7239 -1.714246)
			(stroke
				(width 0.1524)
				(type default)
			)
			(layer "F.SilkS")
		)
		(fp_poly
			(pts
				(xy -3.400044 6.067044) (xy 3.400044 6.067044) (xy 3.400044 0.028956) (xy 2.638044 -0.733044) (xy -2.638044 -0.733044)
				(xy -3.400044 0.028956)
			)
			(stroke
				(width 0)
				(type default)
			)
			(fill no)
			(layer "F.CrtYd")
		)
		(fp_line
			(start -3.400044 6.067044)
			(end 3.400044 6.067044)
			(stroke
				(width 0.1)
				(type default)
			)
			(layer "F.Fab")
		)
		(fp_line
			(start 3.400044 6.067044)
			(end 3.400044 0.028956)
			(stroke
				(width 0.1)
				(type default)
			)
			(layer "F.Fab")
		)
		(fp_line
			(start -3.400044 0.028956)
			(end -3.400044 6.067044)
			(stroke
				(width 0.1)
				(type default)
			)
			(layer "F.Fab")
		)
		(fp_line
			(start 3.400044 0.028956)
			(end 2.638044 -0.733044)
			(stroke
				(width 0.1)
				(type default)
			)
			(layer "F.Fab")
		)
		(fp_line
			(start -2.638044 -0.733044)
			(end -3.400044 0.028956)
			(stroke
				(width 0.1)
				(type default)
			)
			(layer "F.Fab")
		)
		(fp_line
			(start 2.638044 -0.733044)
			(end -2.638044 -0.733044)
			(stroke
				(width 0.1)
				(type default)
			)
			(layer "F.Fab")
		)
		(fp_circle
			(center 0 2.667)
			(end 0 -0.733044)
			(stroke
				(width 0.1)
				(type default)
			)
			(fill no)
			(layer "F.Fab")
		)
		(pad "1" smd rect
			(at 0 0 270)
			(size 0.7874 3.429)
			(layers "F.Cu" "F.Mask" "F.Paste")
			(net "VR_FET_SW_P12V_STBY_PVCCIN_CPU1")
		)
		(pad "2" smd rect
			(at 0 5.334 270)
			(size 0.7874 3.429)
			(layers "F.Cu" "F.Mask" "F.Paste")
			(net "GND")
		)
	)
	(footprint ""
		(layer "F.Cu")
		(at 13.8938 -24.13 90)
		(property "Reference" "C1F18"
			(at 0 0 90)
			(layer "F.SilkS")
			(hide yes)
			(effects
				(font
					(size 1.27 1.27)
				)
			)
		)
		(property "Value" ""
			(at 0 0 90)
			(layer "F.Fab")
			(effects
				(font
					(size 1.27 1.27)
				)
			)
		)
		(duplicate_pad_numbers_are_jumpers no)
		(fp_rect
			(start -0.3048 -0.1016)
			(end 0.3048 0.9906)
			(stroke
				(width 0)
				(type default)
			)
			(fill no)
			(layer "F.CrtYd")
		)
		(fp_line
			(start 0.3048 -0.1016)
			(end -0.3048 -0.1016)
			(stroke
				(width 0.1)
				(type default)
			)
			(layer "F.Fab")
		)
		(fp_line
			(start -0.3048 -0.1016)
			(end -0.3048 0.9906)
			(stroke
				(width 0.1)
				(type default)
			)
			(layer "F.Fab")
		)
		(fp_line
			(start 0.3048 0.9906)
			(end 0.3048 -0.1016)
			(stroke
				(width 0.1)
				(type default)
			)
			(layer "F.Fab")
		)
		(fp_line
			(start -0.3048 0.9906)
			(end 0.3048 0.9906)
			(stroke
				(width 0.1)
				(type default)
			)
			(layer "F.Fab")
		)
		(pad "1" smd rect
			(at 0 0 90)
			(size 0.508 0.508)
			(layers "F.Cu" "F.Mask" "F.Paste")
			(net "P3E_CPU1_PE3_MP_C_TXP<0>")
		)
		(pad "2" smd rect
			(at 0 0.889 90)
			(size 0.508 0.508)
			(layers "F.Cu" "F.Mask" "F.Paste")
			(net "P3E_CPU1_PE3_MP_TXP<0>")
		)
		(zone
			(layer "F.Cu")
			(hatch none 0.5)
			(connect_pads
				(clearance 0)
			)
			(min_thickness 0.25)
			(keepout
				(tracks allowed)
				(vias not_allowed)
				(pads allowed)
				(copperpour not_allowed)
				(footprints allowed)
			)
			(placement
				(enabled no)
				(sheetname "")
			)
			(fill
				(thermal_gap 0.5)
				(thermal_bridge_width 0.5)
				(island_removal_mode 0)
			)
			(polygon
				(pts
					(xy 14.1478 -23.876) (xy 14.5288 -23.876) (xy 14.5288 -24.384) (xy 14.1478 -24.384)
				)
			)
		)
		(zone
			(layer "F.Cu")
			(hatch none 0.5)
			(connect_pads
				(clearance 0)
			)
			(min_thickness 0.25)
			(keepout
				(tracks not_allowed)
				(vias allowed)
				(pads allowed)
				(copperpour not_allowed)
				(footprints allowed)
			)
			(placement
				(enabled no)
				(sheetname "")
			)
			(fill
				(thermal_gap 0.5)
				(thermal_bridge_width 0.5)
				(island_removal_mode 0)
			)
			(polygon
				(pts
					(xy 14.1478 -23.876) (xy 14.5288 -23.876) (xy 14.5288 -24.384) (xy 14.1478 -24.384)
				)
			)
		)
	)
)
